# T6G (Grand Teton) — schematic netlist excerpt (pin names and nets, part order shuffled) for the footprints in the layout excerpt that follows; sources: Cadence DE-HDL packaged netlist, KiCad conversion of 04192023_DAF0TMB3IC0_F0TG_MB_C_brd_V02_OCP.brd

X9  TP_TDR_4P_FTS  TP_TDR_4P_DIP EMPTY  pkg TH  page 260
  S1  = TDR_DIFF_80_IN2_DN
  P1  = T1_GND
  P2  = T1_GND
  S2  = TDR_DIFF_80_IN2_DP

PC532  Q_CAPP  390UF 2.5V 20% ALUM  pkg SMLF  page 225 : A = PVDD11_S3_P1 ; B = GND

(kicad_pcb
	(version 20260206)
	(generator "pcbnew")
	(generator_version "10.0")
	(general
		(thickness 1.6)
		(legacy_teardrops no)
	)
	(paper "A4")
	(title_block
		(title "04192023_DAF0TMB3IC0_F0TG_MB_C_brd_V02_OCP.brd")
		(comment 1 "Grand Teton / footprints 30-31 of 8354")
	)
	(layers
		(0 "F.Cu" signal "TOP")
		(4 "In1.Cu" signal "GND")
		(6 "In2.Cu" signal "IN1")
		(8 "In3.Cu" signal "GND1")
		(10 "In4.Cu" signal "IN2")
		(12 "In5.Cu" signal "GND2")
		(14 "In6.Cu" signal "IN3")
		(16 "In7.Cu" signal "GND3")
		(18 "In8.Cu" signal "VCC")
		(20 "In9.Cu" signal "VCC1")
		(22 "In10.Cu" signal "GND4")
		(24 "In11.Cu" signal "IN4")
		(26 "In12.Cu" signal "GND5")
		(28 "In13.Cu" signal "IN5")
		(30 "In14.Cu" signal "GND6")
		(32 "In15.Cu" signal "IN6")
		(34 "In16.Cu" signal "GND7")
		(2 "B.Cu" signal "BOTTOM")
		(9 "F.Adhes" user "F.Adhesive")
		(11 "B.Adhes" user "B.Adhesive")
		(13 "F.Paste" user "Package Geometry/Pastemask Top")
		(15 "B.Paste" user "Package Geometry/Pastemask Bottom")
		(5 "F.SilkS" user "Ref Des/Silkscreen Top")
		(7 "B.SilkS" user "Ref Des/Silkscreen Bottom")
		(1 "F.Mask" user "Board Geometry/Soldermask Top")
		(3 "B.Mask" user "Board Geometry/Soldermask Bottom")
		(17 "Dwgs.User" user "User.Drawings")
		(19 "Cmts.User" user "User.Comments")
		(21 "Eco1.User" user "User.Eco1")
		(23 "Eco2.User" user "User.Eco2")
		(25 "Edge.Cuts" user "Board Geometry/Outline")
		(27 "Margin" user)
		(31 "F.CrtYd" user "Package Geometry/Place Bound Top")
		(29 "B.CrtYd" user "Package Geometry/Place Bound Bottom")
		(35 "F.Fab" user "Ref Des/Assembly Top")
		(33 "B.Fab" user "Ref Des/Assembly Bottom")
	)
	(footprint ""
		(layer "F.Cu")
		(at 506.598428 -147.926806 -90)
		(property "Reference" "X9"
			(at -1.73355 3.189224 0)
			(unlocked yes)
			(layer "F.SilkS")
			(effects
				(font
					(size 0.7874 0.5842)
					(thickness 0.1524)
				)
				(justify left)
			)
		)
		(property "Value" ""
			(at 0 0 270)
			(layer "F.Fab")
			(effects
				(font
					(size 1.27 1.27)
				)
			)
		)
		(property "Device Type" "TP_TDR_4P_FTS_TH-TP_TDR_4P_DIP,EMPTY,TP15"
			(at 1.30175 1.27 0)
			(unlocked yes)
			(layer "F.Fab")
			(hide yes)
			(effects
				(font
					(size 0.635 0.4064)
					(thickness 0.1524)
				)
			)
		)
		(property "User Part Number" "N_A"
			(at 1.30175 1.27 0)
			(unlocked yes)
			(layer "Cmts.User")
			(hide yes)
			(effects
				(font
					(size 0.635 0.4064)
					(thickness 0.1524)
				)
			)
		)
		(duplicate_pad_numbers_are_jumpers no)
		(fp_line
			(start 0 3.81)
			(end 2.54 3.81)
			(stroke
				(width 0.1524)
				(type default)
			)
			(layer "F.SilkS")
		)
		(fp_line
			(start 2.54 3.81)
			(end 2.54 3.6703)
			(stroke
				(width 0.1524)
				(type default)
			)
			(layer "F.SilkS")
		)
		(fp_line
			(start 0 3.175)
			(end 0 3.81)
			(stroke
				(width 0.1524)
				(type default)
			)
			(layer "F.SilkS")
		)
		(fp_line
			(start 2.54 1.4097)
			(end 2.54 1.1303)
			(stroke
				(width 0.1524)
				(type default)
			)
			(layer "F.SilkS")
		)
		(fp_line
			(start 0 0.635)
			(end 0 1.905)
			(stroke
				(width 0.1524)
				(type default)
			)
			(layer "F.SilkS")
		)
		(fp_line
			(start 2.54 -1.1303)
			(end 2.54 -1.27)
			(stroke
				(width 0.1524)
				(type default)
			)
			(layer "F.SilkS")
		)
		(fp_line
			(start 0 -1.27)
			(end 0 -0.635)
			(stroke
				(width 0.1524)
				(type default)
			)
			(layer "F.SilkS")
		)
		(fp_line
			(start 2.54 -1.27)
			(end 0 -1.27)
			(stroke
				(width 0.1524)
				(type default)
			)
			(layer "F.SilkS")
		)
		(fp_poly
			(pts
				(xy -0.761746 0) (xy -2.285746 0.762) (xy -2.285746 -0.762)
			)
			(stroke
				(width 0)
				(type default)
			)
			(fill yes)
			(layer "F.SilkS")
		)
		(fp_line
			(start 0 3.81)
			(end 2.54 3.81)
			(stroke
				(width 0.1)
				(type default)
			)
			(layer "F.Fab")
		)
		(fp_line
			(start 2.54 3.81)
			(end 2.54 -1.27)
			(stroke
				(width 0.1)
				(type default)
			)
			(layer "F.Fab")
		)
		(fp_line
			(start 0 -1.27)
			(end 0 3.81)
			(stroke
				(width 0.1)
				(type default)
			)
			(layer "F.Fab")
		)
		(fp_line
			(start 2.54 -1.27)
			(end 0 -1.27)
			(stroke
				(width 0.1)
				(type default)
			)
			(layer "F.Fab")
		)
		(fp_poly
			(pts
				(xy -0.761746 0) (xy -2.285746 -0.762) (xy -2.285746 0.762)
			)
			(stroke
				(width 0)
				(type default)
			)
			(fill yes)
			(layer "F.Fab")
		)
		(pad "1" thru_hole circle
			(at 0 0 270)
			(size 1.0033 1.0033)
			(drill 0.249936)
			(layers "*.Cu" "*.Mask")
			(remove_unused_layers no)
			(net "TDR_DIFF_80_IN2_DN")
			(clearance 0.10795)
			(thermal_gap 0.10795)
			(padstack
				(mode front_inner_back)
				(layer "Inner"
					(shape circle)
					(size 0.8001 0.8001)
					(clearance 0.1524)
				)
				(layer "B.Cu"
					(shape circle)
					(size 1.0033 1.0033)
					(clearance 0.10795)
				)
			)
		)
		(pad "2" thru_hole circle
			(at 2.54 0 270)
			(size 1.9939 1.9939)
			(drill 0.249936)
			(layers "*.Cu" "*.Mask")
			(remove_unused_layers no)
			(net "T1_GND")
			(clearance 0.10795)
			(thermal_gap 0.10795)
			(padstack
				(mode front_inner_back)
				(layer "Inner"
					(shape circle)
					(size 0.8001 0.8001)
					(clearance 0.1524)
				)
				(layer "B.Cu"
					(shape circle)
					(size 1.9939 1.9939)
					(clearance 0.10795)
				)
			)
		)
		(pad "3" thru_hole circle
			(at 2.54 2.54 270)
			(size 1.9939 1.9939)
			(drill 0.249936)
			(layers "*.Cu" "*.Mask")
			(remove_unused_layers no)
			(net "T1_GND")
			(clearance 0.10795)
			(thermal_gap 0.10795)
			(padstack
				(mode front_inner_back)
				(layer "Inner"
					(shape circle)
					(size 0.8001 0.8001)
					(clearance 0.1524)
				)
				(layer "B.Cu"
					(shape circle)
					(size 1.9939 1.9939)
					(clearance 0.10795)
				)
			)
		)
		(pad "4" thru_hole circle
			(at 0 2.54 270)
			(size 1.0033 1.0033)
			(drill 0.249936)
			(layers "*.Cu" "*.Mask")
			(remove_unused_layers no)
			(net "TDR_DIFF_80_IN2_DP")
			(clearance 0.10795)
			(thermal_gap 0.10795)
			(padstack
				(mode front_inner_back)
				(layer "Inner"
					(shape circle)
					(size 0.8001 0.8001)
					(clearance 0.1524)
				)
				(layer "B.Cu"
					(shape circle)
					(size 1.0033 1.0033)
					(clearance 0.10795)
				)
			)
		)
	)
	(footprint ""
		(layer "F.Cu")
		(at 188.122306 -332.744572 -90)
		(property "Reference" "PC532"
			(at -4.24434 12.521692 90)
			(unlocked yes)
			(layer "F.SilkS")
			(effects
				(font
					(size 0.7874 0.5842)
					(thickness 0.1524)
				)
				(justify left)
			)
		)
		(property "Value" ""
			(at 0 0 270)
			(layer "F.Fab")
			(effects
				(font
					(size 1.27 1.27)
				)
			)
		)
		(duplicate_pad_numbers_are_jumpers no)
		(fp_line
			(start -1.988058 2.750058)
			(end 2.750058 2.750058)
			(stroke
				(width 0.1524)
				(type default)
			)
			(layer "F.SilkS")
		)
		(fp_line
			(start 2.750058 2.750058)
			(end 2.750058 0.9398)
			(stroke
				(width 0.1524)
				(type default)
			)
			(layer "F.SilkS")
		)
		(fp_line
			(start -2.750058 1.988058)
			(end -1.988058 2.750058)
			(stroke
				(width 0.1524)
				(type default)
			)
			(layer "F.SilkS")
		)
		(fp_line
			(start -2.750058 0.9398)
			(end -2.750058 1.988058)
			(stroke
				(width 0.1524)
				(type default)
			)
			(layer "F.SilkS")
		)
		(fp_line
			(start 2.750058 -0.9398)
			(end 2.750058 -2.750058)
			(stroke
				(width 0.1524)
				(type default)
			)
			(layer "F.SilkS")
		)
		(fp_line
			(start -2.750058 -1.988058)
			(end -2.750058 -0.9398)
			(stroke
				(width 0.1524)
				(type default)
			)
			(layer "F.SilkS")
		)
		(fp_line
			(start -1.988058 -2.750058)
			(end -2.750058 -1.988058)
			(stroke
				(width 0.1524)
				(type default)
			)
			(layer "F.SilkS")
		)
		(fp_line
			(start 2.750058 -2.750058)
			(end -1.988058 -2.750058)
			(stroke
				(width 0.1524)
				(type default)
			)
			(layer "F.SilkS")
		)
		(fp_line
			(start -2.750058 2.750058)
			(end 2.750058 2.750058)
			(stroke
				(width 0.1)
				(type default)
			)
			(layer "F.Fab")
		)
		(fp_line
			(start 2.750058 2.750058)
			(end 2.750058 -2.750058)
			(stroke
				(width 0.1)
				(type default)
			)
			(layer "F.Fab")
		)
		(fp_line
			(start -2.750058 -2.750058)
			(end -2.750058 2.750058)
			(stroke
				(width 0.1)
				(type default)
			)
			(layer "F.Fab")
		)
		(fp_line
			(start 2.750058 -2.750058)
			(end -2.750058 -2.750058)
			(stroke
				(width 0.1)
				(type default)
			)
			(layer "F.Fab")
		)
		(pad "1" smd rect
			(at -2.199894 0)
			(size 1.6002 3.0226)
			(layers "F.Cu" "F.Mask" "F.Paste")
			(net "PVDD11_S3_P1")
		)
		(pad "2" smd rect
			(at 2.199894 0)
			(size 1.6002 3.0226)
			(layers "F.Cu" "F.Mask" "F.Paste")
			(net "GND")
		)
	)
)
